FILE_TYPE = CONNECTIVITY;
{Allegro Design Entry HDL 17.4-2019 S026 (4007227) 1/17/2022}
"PAGE_NUMBER" = 264;
0"NC";
1"GND\g";
2"P1V8_AUX\g";
3"GND\g";
4"P1V8_AUX\g";
5"P1V8_AUX\g";
6"P3V3_AUX\g";
7"P12V_MEM_CPU0\g";
8"GND\g";
9"GND\g";
10"GND\g";
11"GND\g";
12"P3V3_AUX\g";
13"P12V_MEM_CPU1\g";
14"GND\g";
15"GND\g";
16"GND\g";
17"PU_U38_6";
18"P12V_MEM_CPU0\g";
19"P12V_AUX\g";
20"P12V_MEM_CPU1\g";
21"P12V_AUX\g";
22"P1V8_AUX\g";
23"PWRGD_P12V_MEM_CPU1";
24"TP_P12V_AUX_CPU0_DIMM_ISEN_N"CDS_PHYS_NET_NAME"TP_P12V_AUX_CPU0_DIMM_ISEN_N";
25"TP_P12V_AUX_CPU1_DIMM_ISEN_P"CDS_PHYS_NET_NAME"TP_P12V_AUX_CPU1_DIMM_ISEN_P";
26"TP_P12V_AUX_CPU1_DIMM_ISEN_N"CDS_PHYS_NET_NAME"TP_P12V_AUX_CPU1_DIMM_ISEN_N";
27"TP_P12V_AUX_CPU0_DIMM_ISEN_P"CDS_PHYS_NET_NAME"TP_P12V_AUX_CPU0_DIMM_ISEN_P";
28"PWRGD_P12V_MEM_CPU0_R";
29"PWRGD_P12V_MEM_CPU1_EN_N";
30"PWRGD_P12V_MEM_CPU0";
31"PWRGD_P12V_MEM_CPU1";
32"PWRGD_P12V_MEM_CPU1_EN";
33"PWRGD_P12V_MEM";
34"PWRGD_P12V_MEM_CPU1_R";
35"PWRGD_P12V_MEM_R";
36"PWRGD_P12V_MEM_CPU0_EN_N";
37"PWRGD_P12V_MEM_CPU0_EN";
38"PWRGD_P12V_MEM_CPU0";
%"UNIVERSAL_GND"
"1","(-3750,2150)","0","pure_quanta_power","I16";
;
CDS_LIB"pure_quanta_power"
HDL_POWER"GND";
"A"16;
%"Q_RES"
"1","(-3575,2025)","0","pure_quanta","I17";
;
LOCATION"R1363"
$SEC"1"
CDS_SEC"1"
VALUE"33"
PACK_TYPE"0402LF"
TOLERANCE"5%"
MATERIAL"CHIP"
WATTAGE"1/16W"
BOM_COST"MEM"
CDS_LIB"pure_quanta"
PART_NUMBER"CS03302JB10";
"B"
$PN"2"35;
"A"
$PN"1"33;
%"UNIVERSAL_GND"
"1","(-6175,3725)","0","pure_quanta_power","I23";
;
CDS_LIB"pure_quanta_power"
BOM_COST"VR_SYSTEM"
HDL_POWER"GND";
"A"15;
%"Q_RES"
"2","(-6175,3925)","0","pure_quanta","I24";
;
LOCATION"R1441"
$SEC"1"
CDS_SEC"1"
VALUE"16.9K"
WATTAGE"1/16W"
MATERIAL"CHIP"
PACK_TYPE"0402LF"
TOLERANCE"1%"
BOM_COST"VR_SYSTEM"
CDS_LIB"pure_quanta"
PART_NUMBER"CS31692FB03";
"A"
$PN"1"32;
"B"
$PN"2"15;
%"Q_RES"
"2","(-6175,4425)","0","pure_quanta","I25";
;
LOCATION"R1440"
$SEC"1"
CDS_SEC"1"
PACK_TYPE"0402LF"
VALUE"100K"
MATERIAL"CHIP"
WATTAGE"1/16W"
TOLERANCE"1%"
CDS_LIB"pure_quanta"
BOM_COST"VR_SYSTEM"
PART_NUMBER"CS41002FB09";
"A"
$PN"1"13;
"B"
$PN"2"32;
%"Q_RES"
"2","(-5425,4700)","0","pure_quanta","I26";
;
LOCATION"R1449"
$SEC"1"
CDS_SEC"1"
VALUE"10K"
PACK_TYPE"0402LF"
TOLERANCE"5%"
WATTAGE"1/16W"
MATERIAL"CHIP"
BOM_COST"VR_SYSTEM"
CDS_LIB"pure_quanta"
PART_NUMBER"CS31002JB08";
"A"
$PN"1"12;
"B"
$PN"2"29;
%"Q_RES"
"2","(-6275,5250)","0","pure_quanta","I27";
;
LOCATION"R1443"
$SEC"1"
CDS_SEC"1"
MATERIAL"CHIP"
PACK_TYPE"0402LF"
VALUE"16.9K"
TOLERANCE"1%"
WATTAGE"1/16W"
BOM_COST"VR_SYSTEM"
CDS_LIB"pure_quanta"
PART_NUMBER"CS31692FB03";
"A"
$PN"1"37;
"B"
$PN"2"14;
%"UNIVERSAL_GND"
"1","(-6275,5050)","0","pure_quanta_power","I28";
;
CDS_LIB"pure_quanta_power"
BOM_COST"VR_SYSTEM"
HDL_POWER"GND";
"A"14;
%"UNIVERSAL_POWER"
"1","(-6175,4750)","0","pure_quanta_power","I29";
;
HDL_POWER"P12V_MEM_CPU1"
CDS_LIB"pure_quanta_power"
BOM_COST"VR_SYSTEM";
"A"13;
%"Q_RES"
"2","(-6275,5750)","0","pure_quanta","I30";
;
LOCATION"R1442"
$SEC"1"
CDS_SEC"1"
PACK_TYPE"0402LF"
VALUE"100K"
WATTAGE"1/16W"
MATERIAL"CHIP"
TOLERANCE"1%"
CDS_LIB"pure_quanta"
BOM_COST"VR_SYSTEM"
PART_NUMBER"CS41002FB09";
"A"
$PN"1"7;
"B"
$PN"2"37;
%"UNIVERSAL_POWER"
"1","(-5425,4950)","0","pure_quanta_power","I31";
;
HDL_POWER"P3V3_AUX"
CDS_LIB"pure_quanta_power"
BOM_COST"VR_SYSTEM";
"A"12;
%"UNIVERSAL_GND"
"1","(-5425,5525)","7","pure_quanta_power","I32";
;
CDS_LIB"pure_quanta_power"
BOM_COST"VR_SYSTEM"
HDL_POWER"GND";
"A"11;
%"BSS138DW7F"
"1","(-4800,4150)","0","pure_quanta","I33";
;
LOCATION"Q19"
$SEC"1"
CDS_SEC"1"
VALUE"BSS138DW-7-F"
PART_TYPE"SMLF"
MATERIAL"IC"
NEEDS_NO_SIZE"TRUE"
CDS_LIB"pure_quanta"
PART_NUMBER"BAM01380032";
"D2"
$PN"3"31;
"D1"
$PN"6"29;
"S2"
$PN"4"9;
"G2"
$PN"5"29;
"G1"
$PN"2"32;
"S1"
$PN"1"10;
%"UNIVERSAL_GND"
"1","(-5175,4200)","7","pure_quanta_power","I34";
;
CDS_LIB"pure_quanta_power"
BOM_COST"VR_SYSTEM"
HDL_POWER"GND";
"A"10;
%"UNIVERSAL_GND"
"1","(-4425,4200)","1","pure_quanta_power","I35";
;
CDS_LIB"pure_quanta_power"
BOM_COST"VR_SYSTEM"
HDL_POWER"GND";
"A"9;
%"BSS138DW7F"
"1","(-5050,5475)","0","pure_quanta","I36";
;
LOCATION"Q18"
$SEC"1"
CDS_SEC"1"
MATERIAL"IC"
VALUE"BSS138DW-7-F"
PART_TYPE"SMLF"
NEEDS_NO_SIZE"TRUE"
CDS_LIB"pure_quanta"
PART_NUMBER"BAM01380032";
"D2"
$PN"3"30;
"D1"
$PN"6"36;
"S2"
$PN"4"8;
"G2"
$PN"5"36;
"G1"
$PN"2"37;
"S1"
$PN"1"11;
%"UNIVERSAL_GND"
"1","(-4675,5525)","1","pure_quanta_power","I37";
;
BOM_COST"VR_SYSTEM"
CDS_LIB"pure_quanta_power"
HDL_POWER"GND";
"A"8;
%"UNIVERSAL_POWER"
"1","(-6275,6075)","0","pure_quanta_power","I38";
;
HDL_POWER"P12V_MEM_CPU0"
CDS_LIB"pure_quanta_power"
BOM_COST"VR_SYSTEM";
"A"7;
%"Q_RES"
"2","(-5500,5975)","0","pure_quanta","I39";
;
LOCATION"R1450"
$SEC"1"
CDS_SEC"1"
TOLERANCE"5%"
VALUE"10K"
WATTAGE"1/16W"
MATERIAL"CHIP"
PACK_TYPE"0402LF"
BOM_COST"VR_SYSTEM"
CDS_LIB"pure_quanta"
PART_NUMBER"CS31002JB08";
"A"
$PN"1"6;
"B"
$PN"2"36;
%"UNIVERSAL_POWER"
"1","(-5500,6300)","0","pure_quanta_power","I40";
;
HDL_POWER"P3V3_AUX"
CDS_LIB"pure_quanta_power"
BOM_COST"VR_SYSTEM";
"A"6;
%"Q_RES"
"2","(-4425,5950)","0","pure_quanta","I41";
;
LOCATION"R1457"
$SEC"1"
CDS_SEC"1"
WATTAGE"1/16W"
MATERIAL"CHIP"
TOLERANCE"5%"
VALUE"10K"
PACK_TYPE"0402LF"
CDS_LIB"pure_quanta"
BOM_COST"VR_SYSTEM"
PART_NUMBER"CS31002JB08";
"A"
$PN"1"5;
"B"
$PN"2"30;
%"P1V0_AUX"
"1","(-4425,6225)","0","pure_quanta_power","I42";
;
HDL_POWER"P1V8_AUX"
CDS_LIB"pure_quanta_power";
"A"5;
%"Q_RES"
"2","(-4325,4650)","0","pure_quanta","I43";
;
LOCATION"R1452"
$SEC"1"
CDS_SEC"1"
WATTAGE"1/16W"
MATERIAL"CHIP"
PACK_TYPE"0402LF"
TOLERANCE"5%"
VALUE"10K"
BOM_COST"VR_SYSTEM"
CDS_LIB"pure_quanta"
PART_NUMBER"CS31002JB08";
"A"
$PN"1"4;
"B"
$PN"2"31;
%"P1V0_AUX"
"1","(-4325,4925)","0","pure_quanta_power","I45";
;
HDL_POWER"P1V8_AUX"
CDS_LIB"pure_quanta_power";
"A"4;
%"Q_CAP"
"1","(-3750,2350)","2","pure_quanta","I47";
;
LOCATION"C347"
$SEC"1"
CDS_SEC"1"
VALUE"0.1UF"
PACK_TYPE"0402"
MATERIAL"X7R"
TOLERANCE"10%"
VOLTAGE"25V"
CDS_LIB"pure_quanta"
PART_NUMBER"CH4104K1B00";
"B"
$PN"2"16;
"A"
$PN"1"22;
%"P1V0_AUX"
"1","(-4000,2600)","0","pure_quanta_power","I48";
;
HDL_POWER"P1V8_AUX"
CDS_LIB"pure_quanta_power";
"A"22;
%"Q_CAP"
"1","(-3225,1775)","0","pure_quanta","I49";
;
LOCATION"C5014"
$SEC"1"
CDS_SEC"1"
MATERIAL"X7R"
VALUE"1000PF"
PACK_TYPE"0402"
VOLTAGE"50V"
TOLERANCE"5%"
CDS_LIB"pure_quanta"
PART_NUMBER"TMP_QCH21006JB10";
"B"
$PN"2"3;
"A"
$PN"1"35;
%"Q_RES"
"1","(-5475,2075)","0","pure_quanta","I5";
;
LOCATION"R1459"
$SEC"1"
CDS_SEC"1"
VALUE"33"
PACK_TYPE"0402LF"
TOLERANCE"5%"
MATERIAL"CHIP"
WATTAGE"1/16W"
BOM_COST"OCP3.0 "
CDS_LIB"pure_quanta"
PART_NUMBER"CS03302JB10";
"B"
$PN"2"34;
"A"
$PN"1"23;
%"UNIVERSAL_GND"
"1","(-3225,1525)","0","pure_quanta_power","I50";
;
BOM_COST"VR_SYSTEM"
CDS_LIB"pure_quanta_power"
HDL_POWER"GND";
"A"3;
%"Q_RES"
"2","(-6800,2225)","2","pure_quanta","I51";
;
LOCATION"R6504"
$SEC"1"
CDS_SEC"1"
TOLERANCE"1%"
PACK_TYPE"0402LF"
WATTAGE"1/16W"
MATERIAL"CHIP"
VALUE"10K"
CDS_LIB"pure_quanta"
PART_NUMBER"CS31002FB08";
"A"
$PN"1"2;
"B"
$PN"2"17;
%"P1V0_AUX"
"1","(-6800,2625)","0","pure_quanta_power","I52";
;
HDL_POWER"P1V8_AUX"
CDS_LIB"pure_quanta_power";
"A"2;
%"UNIVERSAL_POWER"
"1","(-8825,4400)","0","pure_quanta_power","I53";
;
HDL_POWER"P12V_AUX"
CDS_LIB"pure_quanta_power";
"A"21;
%"Q_RES_4P_12"
"1","(-7925,4050)","1","pure_quanta","I54";
;
LOCATION"R1837"
$SEC"1"
CDS_SEC"1"
MATERIAL"CHIP"
TOLERANCE"1%"
WATTAGE"3W"
VALUE"0.001"
PART_TYPE"SMLF"
NEEDS_NO_SIZE"TRUE"
CDS_LMAN_SYM_OUTLINE"-50,75,50,-75"
CDS_LIB"pure_quanta"
PART_NUMBER"SP_CS+001DFR10";
"4"
$PN"4"26;
"3"
$PN"3"25;
"2"
$PN"2"20;
"1"
$PN"1"21;
%"UNIVERSAL_POWER"
"1","(-7075,4400)","0","pure_quanta_power","I55";
;
HDL_POWER"P12V_MEM_CPU1"
CDS_LIB"pure_quanta_power";
"A"20;
%"UNIVERSAL_POWER"
"1","(-8850,5850)","0","pure_quanta_power","I56";
;
HDL_POWER"P12V_AUX"
CDS_LIB"pure_quanta_power";
"A"19;
%"UNIVERSAL_POWER"
"1","(-7100,5850)","0","pure_quanta_power","I57";
;
HDL_POWER"P12V_MEM_CPU0"
CDS_LIB"pure_quanta_power";
"A"18;
%"Q_RES_4P_12"
"1","(-7950,5500)","1","pure_quanta","I58";
;
LOCATION"R1838"
$SEC"1"
CDS_SEC"1"
WATTAGE"3W"
MATERIAL"CHIP"
VALUE"0.001"
TOLERANCE"1%"
PART_TYPE"SMLF"
NEEDS_NO_SIZE"TRUE"
CDS_LMAN_SYM_OUTLINE"-50,75,50,-75"
CDS_LIB"pure_quanta"
PART_NUMBER"SP_CS+001DFR10";
"4"
$PN"4"24;
"3"
$PN"3"27;
"2"
$PN"2"18;
"1"
$PN"1"19;
%"Q_RES"
"1","(-5475,2175)","0","pure_quanta","I6";
;
LOCATION"R1458"
$SEC"1"
CDS_SEC"1"
VALUE"33"
PACK_TYPE"0402LF"
TOLERANCE"5%"
MATERIAL"CHIP"
WATTAGE"1/16W"
CDS_LIB"pure_quanta"
BOM_COST"OCP3.0 "
PART_NUMBER"CS03302JB10";
"B"
$PN"2"28;
"A"
$PN"1"38;
%"UNIVERSAL_GND"
"1","(-4875,1725)","0","pure_quanta_power","I7";
;
CDS_LIB"pure_quanta_power"
BOM_COST"VR_SYSTEM"
HDL_POWER"GND";
"A"1;
%"SN74LVC1G11DCKR"
"1","(-4500,2025)","0","pure_quanta","I8";
;
LOCATION"U38"
$SEC"1"
CDS_SEC"1"
VALUE"SN74LVC1G11DCKR"
MATERIAL"IC"
PART_TYPE"SMLF"
CDS_LIB"pure_quanta"
NEEDS_NO_SIZE"TRUE"
CDS_LMAN_SYM_OUTLINE"-150,200,150,-200"
PART_NUMBER"ALLVC1G1000";
"GND"
$PN"2"1;
"Y"
$PN"4"33;
"VCC"
$PN"5"22;
"C"
$PN"6"17;
"B"
$PN"3"34;
"A"
$PN"1"28;
END.
